(kicad_pcb
	(version 20260206)
	(generator "pcbnew")
	(generator_version "10.0")
	(general
		(thickness 1.6)
		(legacy_teardrops no)
	)
	(paper "A4")
	(title_block
		(title "04192023_DAF0TMB3IC0_F0TG_MB_C_brd_V02_OCP.brd")
		(comment 1 "Grand Teton / footprints 2098-2099 of 8354")
	)
	(layers
		(0 "F.Cu" signal "TOP")
		(4 "In1.Cu" signal "GND")
		(6 "In2.Cu" signal "IN1")
		(8 "In3.Cu" signal "GND1")
		(10 "In4.Cu" signal "IN2")
		(12 "In5.Cu" signal "GND2")
		(14 "In6.Cu" signal "IN3")
		(16 "In7.Cu" signal "GND3")
		(18 "In8.Cu" signal "VCC")
		(20 "In9.Cu" signal "VCC1")
		(22 "In10.Cu" signal "GND4")
		(24 "In11.Cu" signal "IN4")
		(26 "In12.Cu" signal "GND5")
		(28 "In13.Cu" signal "IN5")
		(30 "In14.Cu" signal "GND6")
		(32 "In15.Cu" signal "IN6")
		(34 "In16.Cu" signal "GND7")
		(2 "B.Cu" signal "BOTTOM")
		(9 "F.Adhes" user "F.Adhesive")
		(11 "B.Adhes" user "B.Adhesive")
		(13 "F.Paste" user "Package Geometry/Pastemask Top")
		(15 "B.Paste" user "Package Geometry/Pastemask Bottom")
		(5 "F.SilkS" user "Ref Des/Silkscreen Top")
		(7 "B.SilkS" user "Ref Des/Silkscreen Bottom")
		(1 "F.Mask" user "Board Geometry/Soldermask Top")
		(3 "B.Mask" user "Board Geometry/Soldermask Bottom")
		(17 "Dwgs.User" user "User.Drawings")
		(19 "Cmts.User" user "User.Comments")
		(21 "Eco1.User" user "User.Eco1")
		(23 "Eco2.User" user "User.Eco2")
		(25 "Edge.Cuts" user "Board Geometry/Outline")
		(27 "Margin" user)
		(31 "F.CrtYd" user "Package Geometry/Place Bound Top")
		(29 "B.CrtYd" user "Package Geometry/Place Bound Bottom")
		(35 "F.Fab" user "Ref Des/Assembly Top")
		(33 "B.Fab" user "Ref Des/Assembly Bottom")
	)
	(footprint ""
		(layer "F.Cu")
		(at 341.441786 -416.899344 -90)
		(property "Reference" "C6525"
			(at 0 0 270)
			(layer "F.SilkS")
			(hide yes)
			(effects
				(font
					(size 1.27 1.27)
				)
			)
		)
		(property "Value" ""
			(at 0 0 270)
			(layer "F.Fab")
			(effects
				(font
					(size 1.27 1.27)
				)
			)
		)
		(duplicate_pad_numbers_are_jumpers no)
		(fp_line
			(start -0.299974 0.150114)
			(end -0.299974 -0.150114)
			(stroke
				(width 0.1)
				(type default)
			)
			(layer "F.Fab")
		)
		(fp_line
			(start 0.299974 0.150114)
			(end -0.299974 0.150114)
			(stroke
				(width 0.1)
				(type default)
			)
			(layer "F.Fab")
		)
		(fp_line
			(start -0.299974 -0.150114)
			(end 0.299974 -0.150114)
			(stroke
				(width 0.1)
				(type default)
			)
			(layer "F.Fab")
		)
		(fp_line
			(start 0.299974 -0.150114)
			(end 0.299974 0.150114)
			(stroke
				(width 0.1)
				(type default)
			)
			(layer "F.Fab")
		)
		(pad "1" smd rect
			(at -0.2667 0 270)
			(size 0.3048 0.381)
			(layers "F.Cu" "F.Mask" "F.Paste")
			(net "P5E_CPU0_P0_TX_BUF_C_DP<12>")
		)
		(pad "2" smd rect
			(at 0.2667 0 270)
			(size 0.3048 0.381)
			(layers "F.Cu" "F.Mask" "F.Paste")
			(net "P5E_CPU0_P0_TX_BUF_DP<12>")
		)
	)
	(footprint ""
		(layer "F.Cu")
		(at 140.886942 -107.683046)
		(property "Reference" "R336"
			(at 0 0 0)
			(layer "F.SilkS")
			(hide yes)
			(effects
				(font
					(size 1.27 1.27)
				)
			)
		)
		(property "Value" ""
			(at 0 0 0)
			(layer "F.Fab")
			(effects
				(font
					(size 1.27 1.27)
				)
			)
		)
		(duplicate_pad_numbers_are_jumpers no)
		(fp_line
			(start -0.7874 -0.4064)
			(end 0.7874 -0.4064)
			(stroke
				(width 0.1524)
				(type default)
			)
			(layer "F.SilkS")
		)
		(fp_line
			(start -0.7874 0.4064)
			(end -0.7874 -0.4064)
			(stroke
				(width 0.1524)
				(type default)
			)
			(layer "F.SilkS")
		)
		(fp_line
			(start 0.7874 -0.4064)
			(end 0.7874 0.4064)
			(stroke
				(width 0.1524)
				(type default)
			)
			(layer "F.SilkS")
		)
		(fp_line
			(start 0.7874 0.4064)
			(end -0.7874 0.4064)
			(stroke
				(width 0.1524)
				(type default)
			)
			(layer "F.SilkS")
		)
		(fp_line
			(start -0.67945 -0.305054)
			(end -0.12065 -0.305054)
			(stroke
				(width 0.1)
				(type default)
			)
			(layer "F.Fab")
		)
		(fp_line
			(start -0.67945 0.3048)
			(end -0.67945 -0.305054)
			(stroke
				(width 0.1)
				(type default)
			)
			(layer "F.Fab")
		)
		(fp_line
			(start -0.12065 -0.305054)
			(end -0.12065 -0.2794)
			(stroke
				(width 0.1)
				(type default)
			)
			(layer "F.Fab")
		)
		(fp_line
			(start -0.12065 -0.2794)
			(end 0.12065 -0.2794)
			(stroke
				(width 0.1)
				(type default)
			)
			(layer "F.Fab")
		)
		(fp_line
			(start -0.12065 0.2794)
			(end -0.12065 0.3048)
			(stroke
				(width 0.1)
				(type default)
			)
			(layer "F.Fab")
		)
		(fp_line
			(start -0.12065 0.3048)
			(end -0.67945 0.3048)
			(stroke
				(width 0.1)
				(type default)
			)
			(layer "F.Fab")
		)
		(fp_line
			(start 0.120396 0.2794)
			(end -0.12065 0.2794)
			(stroke
				(width 0.1)
				(type default)
			)
			(layer "F.Fab")
		)
		(fp_line
			(start 0.120396 0.3048)
			(end 0.120396 0.2794)
			(stroke
				(width 0.1)
				(type default)
			)
			(layer "F.Fab")
		)
		(fp_line
			(start 0.12065 -0.3048)
			(end 0.67945 -0.3048)
			(stroke
				(width 0.1)
				(type default)
			)
			(layer "F.Fab")
		)
		(fp_line
			(start 0.12065 -0.2794)
			(end 0.12065 -0.3048)
			(stroke
				(width 0.1)
				(type default)
			)
			(layer "F.Fab")
		)
		(fp_line
			(start 0.67945 -0.3048)
			(end 0.67945 0.3048)
			(stroke
				(width 0.1)
				(type default)
			)
			(layer "F.Fab")
		)
		(fp_line
			(start 0.67945 0.3048)
			(end 0.120396 0.3048)
			(stroke
				(width 0.1)
				(type default)
			)
			(layer "F.Fab")
		)
		(pad "1" smd circle
			(at -0.40005 0)
			(size 0 0)
			(layers "F.Cu" "F.Mask" "F.Paste")
			(net "P12V_AUX")
		)
		(pad "2" smd circle
			(at 0.40005 0)
			(size 0 0)
			(layers "F.Cu" "F.Mask" "F.Paste")
			(net "VR_P5V_EN_N")
		)
	)
)
